FILE_TYPE = CONNECTIVITY;
{Allegro Design Entry HDL 17.2-2016 S081 (4005846) 1/11/2022}
"PAGE_NUMBER" = 249;
0"NC";
1"P5V_AUX\g";
2"PVCC1_AUX\g";
3"P3V3_AUX\g";
4"P12V_AUX\g";
5"PVCC1_AUX\g";
6"PVCC1_AUX\g";
7"P3V3_AUX\g";
8"P1V8_PCH_AUX\g";
9"GND\g";
10"GND\g";
11"GND\g";
12"GND\g";
13"GND\g";
14"GND\g";
15"GND\g";
16"GND\g";
17"GND\g";
18"P1V8_PCH_AUX_VCC";
19"PWRGD_P1V8_PCH_AUX";
20"SW_P1V8_PCH_AUX_SW";
21"SW_P1V8_PCH_AUX_BST";
22"PWRGD_P1V8_PCH_AUX_R"CDS_PHYS_NET_NAME"PWRGD_P1V8_PCH_AUX_R";
23"SW_P1V8_PCH_AUX_FLT";
24"FM_PCH_P1V8_AUX_EN_R"CDS_PHYS_NET_NAME"FM_PCH_P1V8_AUX_EN_R";
25"P1V8_PCH_AUX_MODE";
26"FM_PCH_P1V8_AUX_EN"CDS_PHYS_NET_NAME"FM_PCH_P1V8_AUX_EN";
%"UNIVERSAL_POWER"
"1","(-5300,4075)","0","logical_power","I1";
;
HDL_POWER"P5V_AUX"
CDS_LIB"logical_power";
"A"1;
%"UNIVERSAL_GND"
"1","(-4850,5800)","0","logical_power","I10";
;
CDS_LIB"logical_power"
HDL_POWER"GND";
"A"11;
%"Q_RES"
"1","(-4500,5950)","0","pure_quanta","I11";
;
PART_NUMBER"CS21002FB06"
PACK_TYPE"0402LF"
MATERIAL"EMPTY"
VALUE"1K"
WATTAGE"1/16W"
TOLERANCE"1%"
LOCATION"PR1850"
CDS_LIB"pure_quanta"
$SEC"1"
CDS_SEC"1";
"B"
$PN"2"24;
"A"
$PN"1"11;
%"GND"
"1","(-6350,6775)","0","logical_power","I13";
;
SIZE"1B"
CDS_LIB"logical_power"
HDL_POWER"GND";
"A<SIZE-1..0>\NAC"12;
%"Q_CAP"
"1","(-6350,7025)","0","pure_quanta","I14";
;
PART_NUMBER"CH4106K1B01"
MATERIAL"X7R"
PACK_TYPE"C0402"
VALUE"100NF"
VOLTAGE"50V"
TOLERANCE"10%"
LOCATION"PC1651"
CDS_LIB"pure_quanta"
$SEC"1"
CDS_SEC"1";
"B"
$PN"2"12;
"A"
$PN"1"4;
%"VCCAUX15"
"1","(-6350,7425)","0","logical_power","I15";
;
HDL_POWER"P12V_AUX"
BOM_COST"VR_PCH"
CDS_LIB"logical_power";
"A"4;
%"Q_INDUCTOR"
"1","(-5975,7250)","0","pure_quanta","I16";
;
PART_NUMBER"CX220TN1001"
MATERIAL"IND"
PACK_TYPE"SMLF"
VALUE"BLM18SN220TN1D/8000MA"
LOCATION"PL16"
CDS_LIB"pure_quanta"
NEEDS_NO_SIZE"TRUE"
$SEC"1"
CDS_SEC"1";
"1"
$PN"1"4;
"2"
$PN"2"23;
%"Q_RES"
"1","(-5000,6250)","0","pure_quanta","I17";
;
PART_NUMBER"CS00002JB13"
MATERIAL"CHIP"
TOLERANCE"5%"
VALUE"0"
LOCATION"R2358"
CDS_LIB"pure_quanta"
WATTAGE"1/16W"
PACK_TYPE"0402LF"
$SEC"1"
CDS_SEC"1";
"B"
$PN"2"24;
"A"
$PN"1"26;
%"UNIVERSAL_GND"
"1","(-5475,6700)","0","logical_power","I18";
;
CDS_LIB"logical_power"
HDL_POWER"GND";
"A"13;
%"Q_CAP"
"1","(-5475,7050)","0","pure_quanta","I19";
;
PART_NUMBER"CH6103KEA01"
PACK_TYPE"C0805"
VALUE"10UF"
TOLERANCE"10%"
MATERIAL"X6S"
VOLTAGE"16V"
LOCATION"PC1232"
CDS_LIB"pure_quanta"
$SEC"1"
CDS_SEC"1";
"B"
$PN"2"13;
"A"
$PN"1"23;
%"Q_RES"
"1","(-4750,3950)","0","pure_quanta","I2";
;
PART_NUMBER"CS00002JB13"
MATERIAL"EMPTY"
PACK_TYPE"0402LF"
TOLERANCE"5%"
VALUE"0"
WATTAGE"1/16W"
LOCATION"PR396"
CDS_LIB"pure_quanta"
$SEC"1"
CDS_SEC"1";
"B"
$PN"2"5;
"A"
$PN"1"1;
%"Q_CAP"
"1","(-5025,7050)","0","pure_quanta","I20";
;
PART_NUMBER"CH6103KEA01"
MATERIAL"X6S"
PACK_TYPE"C0805"
VOLTAGE"16V"
TOLERANCE"10%"
VALUE"10UF"
LOCATION"PC1233"
CDS_LIB"pure_quanta"
$SEC"1"
CDS_SEC"1";
"B"
$PN"2"13;
"A"
$PN"1"23;
%"Q_CAP"
"1","(-4600,7050)","0","pure_quanta","I21";
;
PART_NUMBER"CH4106K1B01"
MATERIAL"X7R"
PACK_TYPE"C0402"
VOLTAGE"50V"
VALUE"100NF"
TOLERANCE"10%"
LOCATION"PC1234"
CDS_LIB"pure_quanta"
LOCATION"PC1234"
$SEC"1"
CDS_SEC"1";
"B"
$PN"2"13;
"A"
$PN"1"23;
%"UNIVERSAL_POWER"
"1","(-4150,4100)","0","logical_power","I22";
;
HDL_POWER"PVCC1_AUX"
CDS_LIB"logical_power";
"A"5;
%"UNIVERSAL_POWER"
"1","(-4150,4500)","0","logical_power","I23";
;
HDL_POWER"PVCC1_AUX"
CDS_LIB"logical_power";
"A"6;
%"Q_RES"
"2","(-4325,5150)","0","pure_quanta","I24";
;
PART_NUMBER"CS41502FB04"
MATERIAL"CHIP"
VALUE"150K"
WATTAGE"1/16W"
TOLERANCE"1%"
PACK_TYPE"0402LF"
LOCATION"PR1330"
CDS_LIB"pure_quanta"
$SEC"1"
CDS_SEC"1";
"A"
$PN"1"25;
"B"
$PN"2"14;
%"UNIVERSAL_GND"
"1","(-4325,4900)","0","logical_power","I25";
;
CDS_LIB"logical_power"
HDL_POWER"GND";
"A"14;
%"NB682GDZ"
"1","(-3150,6075)","0","pure_quanta","I26";
;
PART_NUMBER"AL000682001"
VALUE"NB682GD-Z"
PART_TYPE"SMLF"
MATERIAL"IC"
LOCATION"PU74"
SEC_TYPE""
CDS_LIB"pure_quanta"
NEEDS_NO_SIZE"TRUE"
CDS_LMAN_SYM_OUTLINE"-250,725,250,-725"
SEC"1";
"3V3"
$PN"10"18;
"SW"
$PN"8"20;
"VOUT"
$PN"12"8;
"MODE"
$PN"7"25;
"C0"
$PN"4"10;
"C1"
$PN"3"18;
"LP# \B"
$PN"6"18;
"AGND"
$PN"11"15;
"BST"
$PN"9"21;
"EN"
$PN"5"24;
"PGND"
$PN"2"15;
"PG"
$PN"13"22;
"VIN"
$PN"1"23;
%"UNIVERSAL_GND"
"1","(-2650,4950)","0","logical_power","I27";
;
CDS_LIB"logical_power"
HDL_POWER"GND";
"A"15;
%"Q_CAP"
"1","(-925,6050)","0","pure_quanta","I28";
;
PART_NUMBER"CH4106K1B01"
TOLERANCE"10%"
VOLTAGE"50V"
MATERIAL"X7R"
PACK_TYPE"C0402"
VALUE"100NF"
LOCATION"PC1236"
CDS_LIB"pure_quanta"
$SEC"1"
CDS_SEC"1";
"B"
$PN"2"17;
"A"
$PN"1"8;
%"Q_CAP"
"1","(-525,6050)","0","pure_quanta","I29";
;
PART_NUMBER"CH622KMEA03"
VALUE"22UF"
MATERIAL"X6S"
TOLERANCE"20%"
PACK_TYPE"C0805"
VOLTAGE"4V"
LOCATION"PC1237"
BOM_COST"VR_PCH"
CDS_LIB"pure_quanta"
$SEC"1"
CDS_SEC"1";
"B"
$PN"2"17;
"A"
$PN"1"8;
%"UNIVERSAL_GND"
"1","(-5750,4900)","0","logical_power","I3";
;
CDS_LIB"logical_power"
HDL_POWER"GND";
"A"9;
%"Q_CAP"
"1","(-1875,6475)","0","pure_quanta","I30";
;
PART_NUMBER"CH4224K1B01"
MATERIAL"X7R"
TOLERANCE"10%"
VOLTAGE"25V"
PACK_TYPE"C0402"
VALUE"0.22UF"
LOCATION"PC1235"
CDS_LIB"pure_quanta"
$SEC"1"
CDS_SEC"1";
"B"
$PN"2"20;
"A"
$PN"1"21;
%"Q_RES"
"2","(-1875,7125)","0","pure_quanta","I31";
;
PART_NUMBER"CS31002FB08"
VALUE"10K"
TOLERANCE"1%"
WATTAGE"1/16W"
PACK_TYPE"0402LF"
MATERIAL"CHIP"
LOCATION"R2359"
BOM_COST"VR_PCH"
CDS_LIB"pure_quanta"
$SEC"1"
CDS_SEC"1";
"A"
$PN"1"7;
"B"
$PN"2"22;
%"UNIVERSAL_POWER"
"1","(-1875,7375)","0","logical_power","I32";
;
HDL_POWER"P3V3_AUX"
CDS_LIB"logical_power";
"A"7;
%"Q_RES"
"1","(-1325,6750)","0","pure_quanta","I34";
;
PART_NUMBER"CS00002JB13"
MATERIAL"CHIP"
TOLERANCE"5%"
VALUE"0"
LOCATION"R2360"
CDS_LIB"pure_quanta"
WATTAGE"1/16W"
PACK_TYPE"0402LF"
$SEC"1"
CDS_SEC"1";
"B"
$PN"2"19;
"A"
$PN"1"22;
%"UNIVERSAL_GND"
"1","(-775,6325)","0","logical_power","I35";
;
CDS_LIB"logical_power"
HDL_POWER"GND";
"A"16;
%"Q_CAP"
"1","(-775,6575)","0","pure_quanta","I36";
;
PART_NUMBER"CH31006KB18"
PACK_TYPE"C0402"
MATERIAL"X7R"
TOLERANCE"10%"
VALUE"0.01UF"
VOLTAGE"50V"
LOCATION"C2287"
CDS_LIB"pure_quanta"
$SEC"1"
CDS_SEC"1";
"B"
$PN"2"16;
"A"
$PN"1"19;
%"Q_CAP"
"1","(-150,6050)","0","pure_quanta","I37";
;
PART_NUMBER"CH622KMEA03"
VALUE"22UF"
TOLERANCE"20%"
MATERIAL"X6S"
PACK_TYPE"C0805"
VOLTAGE"4V"
LOCATION"PC1238"
CDS_LIB"pure_quanta"
BOM_COST"VR_PCH"
$SEC"1"
CDS_SEC"1";
"B"
$PN"2"17;
"A"
$PN"1"8;
%"Q_CAP"
"1","(225,6050)","0","pure_quanta","I38";
;
PART_NUMBER"CH622KMEA03"
VALUE"22UF"
PACK_TYPE"C0805"
MATERIAL"X6S"
VOLTAGE"4V"
TOLERANCE"20%"
LOCATION"PC1239"
CDS_LIB"pure_quanta"
BOM_COST"VR_PCH"
$SEC"1"
CDS_SEC"1";
"B"
$PN"2"17;
"A"
$PN"1"8;
%"Q_CAP"
"1","(600,6050)","0","pure_quanta","I39";
;
PART_NUMBER"CH622KMEA03"
MATERIAL"X6S"
TOLERANCE"20%"
VALUE"22UF"
PACK_TYPE"C0805"
VOLTAGE"4V"
LOCATION"PC1240"
BOM_COST"VR_PCH"
CDS_LIB"pure_quanta"
$SEC"1"
CDS_SEC"1";
"B"
$PN"2"17;
"A"
$PN"1"8;
%"Q_CAP"
"1","(-5750,5175)","0","pure_quanta","I4";
;
PART_NUMBER"CH5104KEB02"
PACK_TYPE"C0402"
VOLTAGE"25V"
MATERIAL"X6S"
TOLERANCE"10%"
VALUE"1UF"
LOCATION"PC1642"
CDS_LIB"pure_quanta"
SEC_TYPE"C0402"
BOM_COST"VR_PCH"
SEC"1";
"B"
$PN"2"9;
"A"
$PN"1"18;
%"UNIVERSAL_GND"
"1","(1100,5675)","0","logical_power","I40";
;
CDS_LIB"logical_power"
HDL_POWER"GND";
"A"17;
%"Q_CAP"
"1","(975,6050)","0","pure_quanta","I41";
;
PART_NUMBER"CH622KMEA03"
VOLTAGE"4V"
VALUE"22UF"
PACK_TYPE"C0805"
TOLERANCE"20%"
MATERIAL"X6S"
LOCATION"PC1241"
BOM_COST"VR_PCH"
CDS_LIB"pure_quanta"
$SEC"1"
CDS_SEC"1";
"B"
$PN"2"17;
"A"
$PN"1"8;
%"Q_RES"
"2","(1375,6025)","0","pure_quanta","I42";
;
PART_NUMBER"CS14702FB04"
TOLERANCE"1%"
WATTAGE"1/16W"
PACK_TYPE"0402LF"
MATERIAL"CHIP"
VALUE"470"
LOCATION"PR1653"
CDS_LIB"pure_quanta"
$SEC"1"
CDS_SEC"1";
"A"
$PN"1"8;
"B"
$PN"2"17;
%"UNIVERSAL_POWER"
"1","(1775,6475)","0","logical_power","I44";
;
HDL_POWER"P1V8_PCH_AUX"
CDS_LIB"logical_power";
"A"8;
%"Q_INDUCTOR"
"1","(-1175,6275)","0","pure_quanta","I45";
;
PART_NUMBER"CV-2280MZ15"
MATERIAL"IND"
PACK_TYPE"SMLF"
VALUE"2.2UH"
LOCATION"PL170"
BOM_COST"VR_PCH"
NEEDS_NO_SIZE"TRUE"
CDS_LIB"pure_quanta"
$SEC"1"
CDS_SEC"1";
"1"
$PN"1"20;
"2"
$PN"2"8;
%"Q_RES"
"2","(-5750,5600)","0","pure_quanta","I5";
;
PART_NUMBER"CS-5102JB02"
TOLERANCE"5%"
VALUE"5.1"
PACK_TYPE"0402LF"
WATTAGE"1/16W"
MATERIAL"CHIP"
LOCATION"PR1329"
CDS_LIB"pure_quanta"
$SEC"1"
CDS_SEC"1";
"A"
$PN"1"2;
"B"
$PN"2"18;
%"UNIVERSAL_POWER"
"1","(-5750,5825)","0","logical_power","I6";
;
HDL_POWER"PVCC1_AUX"
CDS_LIB"logical_power";
"A"2;
%"UNIVERSAL_POWER"
"1","(-5300,4500)","0","logical_power","I7";
;
HDL_POWER"P3V3_AUX"
CDS_LIB"logical_power";
"A"3;
%"Q_RES"
"1","(-4750,4375)","0","pure_quanta","I8";
;
PART_NUMBER"CS00002JB13"
MATERIAL"CHIP"
VALUE"0"
PACK_TYPE"0402LF"
WATTAGE"1/16W"
TOLERANCE"5%"
LOCATION"PR395"
CDS_LIB"pure_quanta"
$SEC"1"
CDS_SEC"1";
"B"
$PN"2"6;
"A"
$PN"1"3;
%"UNIVERSAL_GND"
"1","(-4600,4900)","0","logical_power","I9";
;
CDS_LIB"logical_power"
HDL_POWER"GND";
"A"10;
END.
